# BASEBOARD_FAB2 (Tioga Pass) — schematic netlist excerpt (pin names and nets, part order shuffled) for the footprints in the layout excerpt that follows; sources: Cadence DE-HDL packaged netlist, KiCad conversion of Wiwynn_Tioga_Pass_MB.brd

J9U2  SCONN288_H44441003  SCONN  pkg PIP  page 82
  \12v\(1)  = P12V_NVDIMM_GHJ
  VSS(93)  = GND
  DQ(4)  = M_J_DQ<4>
  VSS(92)  = GND
  DQ(0)  = M_J_DQ<0>
  VSS(91)  = GND
  DQS9P  = M_J_DQS_DP<9>
  DQS9N  = M_J_DQS_DN<9>
  VSS(90)  = GND
  DQ(6)  = M_J_DQ<6>
  VSS(89)  = GND
  DQ(2)  = M_J_DQ<2>
  VSS(88)  = GND
  DQ(12)  = M_J_DQ<12>
  VSS(87)  = GND
  DQ(8)  = M_J_DQ<8>
  VSS(86)  = GND
  DQS10P  = M_J_DQS_DP<10>
  DQS10N  = M_J_DQS_DN<10>
  VSS(85)  = GND
  DQ(14)  = M_J_DQ<14>
  VSS(84)  = GND
  DQ(10)  = M_J_DQ<10>
  VSS(83)  = GND
  DQ(20)  = M_J_DQ<20>
  VSS(82)  = GND
  DQ(16)  = M_J_DQ<16>
  VSS(81)  = GND
  DQS11P  = M_J_DQS_DP<11>
  DQS11N  = M_J_DQS_DN<11>
  VSS(80)  = GND
  DQ(22)  = M_J_DQ<22>
  VSS(79)  = GND
  DQ(18)  = M_J_DQ<18>
  VSS(78)  = GND
  DQ(28)  = M_J_DQ<28>
  VSS(77)  = GND
  DQ(24)  = M_J_DQ<24>
  VSS(76)  = GND
  DQS12P  = M_J_DQS_DP<12>
  DQS12N  = M_J_DQS_DN<12>
  VSS(75)  = GND
  DQ(30)  = M_J_DQ<30>
  VSS(74)  = GND
  DQ(26)  = M_J_DQ<26>
  VSS(73)  = GND
  CB(4)  = M_J_ECC<4>
  VSS(72)  = GND
  CB(0)  = M_J_ECC<0>
  VSS(71)  = GND
  DQS17P  = M_J_DQS_DP<17>
  DQS17N  = M_J_DQS_DN<17>
  VSS(70)  = GND
  CB(6)  = M_J_ECC<6>
  VSS(69)  = GND
  CB(2)  = M_J_ECC<2>
  VSS(68)  = GND
  RESET_N  = M_GHJ_RST_N
  VDD(25)  = PVDDQ_GHJ
  CKE(0)  = M_J_CKE<2>
  VDD(24)  = PVDDQ_GHJ
  ACT_N  = M_J_ACT_N
  BG(0)  = M_J_BG<0>
  VDD(23)  = PVDDQ_GHJ
  A12  = M_J_MA<12>
  A9  = M_J_MA<9>
  VDD(22)  = PVDDQ_GHJ
  A8  = M_J_MA<8>
  A6  = M_J_MA<6>
  VDD(21)  = PVDDQ_GHJ
  A3  = M_J_MA<3>
  A1  = M_J_MA<1>
  VDD(20)  = PVDDQ_GHJ
  CK0P  = M_J_CLK_DP<2>
  CK0N  = M_J_CLK_DN<2>
  VDD(19)  = PVDDQ_GHJ
  VTT(1)  = PVTT_GHJ
  EVENT_N  = FM_DIMM_EVENT_COD_N
  A0  = M_J_MA<0>
  VDD(18)  = PVDDQ_GHJ
  BA(0)  = M_J_BA<0>
  A16_RAS_N  = M_J_MA<16>
  VDD(17)  = PVDDQ_GHJ
  S0_N  = M_J_CS_N<4>
  VDD(16)  = PVDDQ_GHJ
  A15_CAS_N  = M_J_MA<15>
  ODT(0)  = M_J_ODT<2>
  VDD(15)  = PVDDQ_GHJ
  S1_N  = M_J_CS_N<5>
  VDD(14)  = PVDDQ_GHJ
  ODT(1)  = M_J_ODT<3>
  VDD(13)  = PVDDQ_GHJ
  S2_N_C(0)  = M_J_CS_N<6>
  VSS(67)  = GND
  DQ(36)  = M_J_DQ<36>
  VSS(66)  = GND
  DQ(32)  = M_J_DQ<32>
  VSS(65)  = GND
  DQS13P  = M_J_DQS_DP<13>
  DQS13N  = M_J_DQS_DN<13>
  VSS(64)  = GND
  DQ(38)  = M_J_DQ<38>
  VSS(63)  = GND
  DQ(34)  = M_J_DQ<34>
  VSS(62)  = GND
  DQ(44)  = M_J_DQ<44>
  VSS(61)  = GND
  DQ(40)  = M_J_DQ<40>
  VSS(60)  = GND
  DQS14P  = M_J_DQS_DP<14>
  DQS14N  = M_J_DQS_DN<14>
  VSS(59)  = GND
  DQ(46)  = M_J_DQ<46>
  VSS(58)  = GND
  DQ(42)  = M_J_DQ<42>
  VSS(57)  = GND
  DQ(52)  = M_J_DQ<52>
  VSS(56)  = GND
  DQ(48)  = M_J_DQ<48>
  VSS(55)  = GND
  DQS15P  = M_J_DQS_DP<15>
  DQS15N  = M_J_DQS_DN<15>
  VSS(54)  = GND
  DQ(54)  = M_J_DQ<54>
  VSS(53)  = GND
  DQ(50)  = M_J_DQ<50>
  VSS(52)  = GND
  DQ(60)  = M_J_DQ<60>
  VSS(51)  = GND
  DQ(56)  = M_J_DQ<56>
  VSS(50)  = GND
  DQS16P  = M_J_DQS_DP<16>
  DQS16N  = M_J_DQS_DN<16>
  VSS(49)  = GND
  DQ(62)  = M_J_DQ<62>
  VSS(48)  = GND
  DQ(58)  = M_J_DQ<58>
  VSS(47)  = GND
  SA(0)  = PVPP_GHJ
  SA(1)  = GND
  SCL  = SMB_DDR_GHJ_VPP_SCL
  VPP(4)  = PVPP_GHJ
  VPP(3)  = PVPP_GHJ
  RFU(2)  = TP_CH_J_DIMM_J1_RFU_2
  \12v\(0)  = P12V_NVDIMM_GHJ
  VREFCA  = M_J_VREF
  VSS(46)  = GND
  DQ(5)  = M_J_DQ<5>
  VSS(45)  = GND
  DQ(1)  = M_J_DQ<1>
  VSS(44)  = GND
  DQS0N  = M_J_DQS_DN<0>
  DQS0P  = M_J_DQS_DP<0>
  VSS(43)  = GND
  DQ(7)  = M_J_DQ<7>
  VSS(42)  = GND
  DQ(3)  = M_J_DQ<3>
  VSS(41)  = GND
  DQ(13)  = M_J_DQ<13>
  VSS(40)  = GND
  DQ(9)  = M_J_DQ<9>
  VSS(39)  = GND
  DQS1N  = M_J_DQS_DN<1>
  DQS1P  = M_J_DQS_DP<1>
  VSS(38)  = GND
  DQ(15)  = M_J_DQ<15>
  VSS(37)  = GND
  DQ(11)  = M_J_DQ<11>
  VSS(36)  = GND
  DQ(21)  = M_J_DQ<21>
  VSS(35)  = GND
  DQ(17)  = M_J_DQ<17>
  VSS(34)  = GND
  DQS2N  = M_J_DQS_DN<2>
  DQS2P  = M_J_DQS_DP<2>
  VSS(33)  = GND
  DQ(23)  = M_J_DQ<23>
  VSS(32)  = GND
  DQ(19)  = M_J_DQ<19>
  VSS(31)  = GND
  DQ(29)  = M_J_DQ<29>
  VSS(30)  = GND
  DQ(25)  = M_J_DQ<25>
  VSS(29)  = GND
  DQS3N  = M_J_DQS_DN<3>
  DQS3P  = M_J_DQS_DP<3>
  VSS(28)  = GND
  DQ(31)  = M_J_DQ<31>
  VSS(27)  = GND
  DQ(27)  = M_J_DQ<27>
  VSS(26)  = GND
  CB(5)  = M_J_ECC<5>
  VSS(25)  = GND
  CB(1)  = M_J_ECC<1>
  VSS(24)  = GND
  DQS8N  = M_J_DQS_DN<8>
  DQS8P  = M_J_DQS_DP<8>
  VSS(23)  = GND
  CB(7)  = M_J_ECC<7>
  VSS(22)  = GND
  CB(3)  = M_J_ECC<3>
  VSS(21)  = GND
  CKE(1)  = M_J_CKE<3>
  VDD(12)  = PVDDQ_GHJ
  RFU(0)  = TP_CH_J_DIMM_J1_RFU_0
  VDD(11)  = PVDDQ_GHJ
  BG(1)  = M_J_BG<1>
  ALERT_N  = M_J_ALERT_N
  VDD(10)  = PVDDQ_GHJ
  A11  = M_J_MA<11>
  A7  = M_J_MA<7>
  VDD(9)  = PVDDQ_GHJ
  A5  = M_J_MA<5>
  A4  = M_J_MA<4>
  VDD(8)  = PVDDQ_GHJ
  A2  = M_J_MA<2>
  VDD(7)  = PVDDQ_GHJ
  CK1P  = M_J_CLK_DP<3>
  CK1N  = M_J_CLK_DN<3>
  VDD(6)  = PVDDQ_GHJ
  VTT(0)  = PVTT_GHJ
  PAR  = M_J_PAR
  VDD(5)  = PVDDQ_GHJ
  BA(1)  = M_J_BA<1>
  A10  = M_J_MA<10>
  VDD(4)  = PVDDQ_GHJ
  RFU(1)  = TP_CH_J_DIMM_J1_RFU_1
  A14_WE_N  = M_J_MA<14>
  VDD(3)  = PVDDQ_GHJ
  SAVE_N_NC  = FM_ADR_COMPLETE_GHJ_N
  VDD(2)  = PVDDQ_GHJ
  A13  = M_J_MA<13>
  VDD(1)  = PVDDQ_GHJ
  A17  = M_J_MA<17>
  C(2)  = M_J_C<2>
  VDD(0)  = PVDDQ_GHJ
  S3_N_C(1)  = M_J_CS_N<7>
  SA(2)  = PVPP_GHJ
  VSS(20)  = GND
  DQ(37)  = M_J_DQ<37>
  VSS(19)  = GND
  DQ(33)  = M_J_DQ<33>
  VSS(18)  = GND
  DQS4N  = M_J_DQS_DN<4>
  DQS4P  = M_J_DQS_DP<4>
  VSS(17)  = GND
  DQ(39)  = M_J_DQ<39>
  VSS(16)  = GND
  DQ(35)  = M_J_DQ<35>
  VSS(15)  = GND
  DQ(45)  = M_J_DQ<45>
  VSS(14)  = GND
  DQ(41)  = M_J_DQ<41>
  VSS(13)  = GND
  DQS5N  = M_J_DQS_DN<5>
  DQS5P  = M_J_DQS_DP<5>
  VSS(12)  = GND
  DQ(47)  = M_J_DQ<47>
  VSS(11)  = GND
  DQ(43)  = M_J_DQ<43>
  VSS(10)  = GND
  DQ(53)  = M_J_DQ<53>
  VSS(9)  = GND
  DQ(49)  = M_J_DQ<49>
  VSS(8)  = GND
  DQS6N  = M_J_DQS_DN<6>
  DQS6P  = M_J_DQS_DP<6>
  VSS(7)  = GND
  DQ(55)  = M_J_DQ<55>
  VSS(6)  = GND
  DQ(51)  = M_J_DQ<51>
  VSS(5)  = GND
  DQ(61)  = M_J_DQ<61>
  VSS(4)  = GND
  DQ(57)  = M_J_DQ<57>
  VSS(3)  = GND
  DQS7N  = M_J_DQS_DN<7>
  DQS7P  = M_J_DQS_DP<7>
  VSS(2)  = GND
  DQ(63)  = M_J_DQ<63>
  VSS(1)  = GND
  DQ(59)  = M_J_DQ<59>
  VSS(0)  = GND
  VDDSPD  = PVPP_GHJ
  SDA  = SMB_DDR_GHJ_VPP_SDA
  VPP(1)  = PVPP_GHJ
  VPP(0)  = PVPP_GHJ
  VPP(2)  = PVPP_GHJ

(kicad_pcb
	(version 20260206)
	(generator "pcbnew")
	(generator_version "10.0")
	(general
		(thickness 1.6)
		(legacy_teardrops no)
	)
	(paper "A4")
	(title_block
		(title "Wiwynn_Tioga_Pass_MB.brd")
		(comment 1 "Tioga Pass / footprint 4543 of 4770 (J9U2), pads 250-291 of 291")
	)
	(layers
		(0 "F.Cu" signal "TOP")
		(4 "In1.Cu" signal "L2GND")
		(6 "In2.Cu" signal "L3")
		(8 "In3.Cu" signal "L4GND")
		(10 "In4.Cu" signal "L5")
		(12 "In5.Cu" signal "L6GND")
		(14 "In6.Cu" signal "L7VCC")
		(16 "In7.Cu" signal "L8VCC")
		(18 "In8.Cu" signal "L9GND")
		(20 "In9.Cu" signal "L10")
		(22 "In10.Cu" signal "L11GND")
		(24 "In11.Cu" signal "L12")
		(26 "In12.Cu" signal "L13GND")
		(2 "B.Cu" signal "BOTTOM")
		(9 "F.Adhes" user "F.Adhesive")
		(11 "B.Adhes" user "B.Adhesive")
		(13 "F.Paste" user "Package Geometry/Pastemask Top")
		(15 "B.Paste" user "Package Geometry/Pastemask Bottom")
		(5 "F.SilkS" user "Ref Des/Silkscreen Top")
		(7 "B.SilkS" user "Ref Des/Silkscreen Bottom")
		(1 "F.Mask" user "Board Geometry/Soldermask Top")
		(3 "B.Mask" user "Board Geometry/Soldermask Bottom")
		(17 "Dwgs.User" user "User.Drawings")
		(19 "Cmts.User" user "User.Comments")
		(21 "Eco1.User" user "User.Eco1")
		(23 "Eco2.User" user "User.Eco2")
		(25 "Edge.Cuts" user "Board Geometry/Outline")
		(27 "Margin" user)
		(31 "F.CrtYd" user "Package Geometry/Place Bound Top")
		(29 "B.CrtYd" user "Package Geometry/Place Bound Bottom")
		(35 "F.Fab" user "Ref Des/Assembly Top")
		(33 "B.Fab" user "Ref Des/Assembly Bottom")
	)
	(footprint ""
		(layer "B.Cu")
		(at 29.699458 -5.621782 90)
		(property "Reference" "J9U2"
			(at 2.098548 38.118542 0)
			(unlocked yes)
			(layer "B.SilkS")
			(effects
				(font
					(size 0.7874 0.5842)
					(thickness 0.1524)
				)
				(justify left mirror)
			)
		)
		(property "Value" ""
			(at 0 0 90)
			(layer "B.Fab")
			(effects
				(font
					(size 1.27 1.27)
				)
				(justify mirror)
			)
		)
		(duplicate_pad_numbers_are_jumpers no)
		(pad "247" smd rect
			(at -4.59994 91.799918 270)
			(size 1.8034 0.508)
			(layers "B.Cu" "B.Mask" "B.Paste")
			(net "M_J_DQ<39>")
		)
		(pad "248" smd rect
			(at -4.59994 92.650056 270)
			(size 1.8034 0.508)
			(layers "B.Cu" "B.Mask" "B.Paste")
			(net "GND")
		)
		(pad "249" smd rect
			(at -4.59994 93.49994 270)
			(size 1.8034 0.508)
			(layers "B.Cu" "B.Mask" "B.Paste")
			(net "M_J_DQ<35>")
		)
		(pad "250" smd rect
			(at -4.59994 94.350078 270)
			(size 1.8034 0.508)
			(layers "B.Cu" "B.Mask" "B.Paste")
			(net "GND")
		)
		(pad "251" smd rect
			(at -4.59994 95.199962 270)
			(size 1.8034 0.508)
			(layers "B.Cu" "B.Mask" "B.Paste")
			(net "M_J_DQ<45>")
		)
		(pad "252" smd rect
			(at -4.59994 96.0501 270)
			(size 1.8034 0.508)
			(layers "B.Cu" "B.Mask" "B.Paste")
			(net "GND")
		)
		(pad "253" smd rect
			(at -4.59994 96.899984 270)
			(size 1.8034 0.508)
			(layers "B.Cu" "B.Mask" "B.Paste")
			(net "M_J_DQ<41>")
		)
		(pad "254" smd rect
			(at -4.59994 97.750122 270)
			(size 1.8034 0.508)
			(layers "B.Cu" "B.Mask" "B.Paste")
			(net "GND")
		)
		(pad "255" smd rect
			(at -4.59994 98.600006 270)
			(size 1.8034 0.508)
			(layers "B.Cu" "B.Mask" "B.Paste")
			(net "M_J_DQS_DN<5>")
		)
		(pad "256" smd rect
			(at -4.59994 99.44989 270)
			(size 1.8034 0.508)
			(layers "B.Cu" "B.Mask" "B.Paste")
			(net "M_J_DQS_DP<5>")
		)
		(pad "257" smd rect
			(at -4.59994 100.300028 270)
			(size 1.8034 0.508)
			(layers "B.Cu" "B.Mask" "B.Paste")
			(net "GND")
		)
		(pad "258" smd rect
			(at -4.59994 101.149912 270)
			(size 1.8034 0.508)
			(layers "B.Cu" "B.Mask" "B.Paste")
			(net "M_J_DQ<47>")
		)
		(pad "259" smd rect
			(at -4.59994 102.00005 270)
			(size 1.8034 0.508)
			(layers "B.Cu" "B.Mask" "B.Paste")
			(net "GND")
		)
		(pad "260" smd rect
			(at -4.59994 102.849934 270)
			(size 1.8034 0.508)
			(layers "B.Cu" "B.Mask" "B.Paste")
			(net "M_J_DQ<43>")
		)
		(pad "261" smd rect
			(at -4.59994 103.700072 270)
			(size 1.8034 0.508)
			(layers "B.Cu" "B.Mask" "B.Paste")
			(net "GND")
		)
		(pad "262" smd rect
			(at -4.59994 104.549956 270)
			(size 1.8034 0.508)
			(layers "B.Cu" "B.Mask" "B.Paste")
			(net "M_J_DQ<53>")
		)
		(pad "263" smd rect
			(at -4.59994 105.400094 270)
			(size 1.8034 0.508)
			(layers "B.Cu" "B.Mask" "B.Paste")
			(net "GND")
		)
		(pad "264" smd rect
			(at -4.59994 106.249978 270)
			(size 1.8034 0.508)
			(layers "B.Cu" "B.Mask" "B.Paste")
			(net "M_J_DQ<49>")
		)
		(pad "265" smd rect
			(at -4.59994 107.100116 270)
			(size 1.8034 0.508)
			(layers "B.Cu" "B.Mask" "B.Paste")
			(net "GND")
		)
		(pad "266" smd rect
			(at -4.59994 107.95 270)
			(size 1.8034 0.508)
			(layers "B.Cu" "B.Mask" "B.Paste")
			(net "M_J_DQS_DN<6>")
		)
		(pad "267" smd rect
			(at -4.59994 108.799884 270)
			(size 1.8034 0.508)
			(layers "B.Cu" "B.Mask" "B.Paste")
			(net "M_J_DQS_DP<6>")
		)
		(pad "268" smd rect
			(at -4.59994 109.650022 270)
			(size 1.8034 0.508)
			(layers "B.Cu" "B.Mask" "B.Paste")
			(net "GND")
		)
		(pad "269" smd rect
			(at -4.59994 110.499906 270)
			(size 1.8034 0.508)
			(layers "B.Cu" "B.Mask" "B.Paste")
			(net "M_J_DQ<55>")
		)
		(pad "270" smd rect
			(at -4.59994 111.350044 270)
			(size 1.8034 0.508)
			(layers "B.Cu" "B.Mask" "B.Paste")
			(net "GND")
		)
		(pad "271" smd rect
			(at -4.59994 112.199928 270)
			(size 1.8034 0.508)
			(layers "B.Cu" "B.Mask" "B.Paste")
			(net "M_J_DQ<51>")
		)
		(pad "272" smd rect
			(at -4.59994 113.050066 270)
			(size 1.8034 0.508)
			(layers "B.Cu" "B.Mask" "B.Paste")
			(net "GND")
		)
		(pad "273" smd rect
			(at -4.59994 113.89995 270)
			(size 1.8034 0.508)
			(layers "B.Cu" "B.Mask" "B.Paste")
			(net "M_J_DQ<61>")
		)
		(pad "274" smd rect
			(at -4.59994 114.750088 270)
			(size 1.8034 0.508)
			(layers "B.Cu" "B.Mask" "B.Paste")
			(net "GND")
		)
		(pad "275" smd rect
			(at -4.59994 115.599972 270)
			(size 1.8034 0.508)
			(layers "B.Cu" "B.Mask" "B.Paste")
			(net "M_J_DQ<57>")
		)
		(pad "276" smd rect
			(at -4.59994 116.45011 270)
			(size 1.8034 0.508)
			(layers "B.Cu" "B.Mask" "B.Paste")
			(net "GND")
		)
		(pad "277" smd rect
			(at -4.59994 117.299994 270)
			(size 1.8034 0.508)
			(layers "B.Cu" "B.Mask" "B.Paste")
			(net "M_J_DQS_DN<7>")
		)
		(pad "278" smd rect
			(at -4.59994 118.149878 270)
			(size 1.8034 0.508)
			(layers "B.Cu" "B.Mask" "B.Paste")
			(net "M_J_DQS_DP<7>")
		)
		(pad "279" smd rect
			(at -4.59994 119.000016 270)
			(size 1.8034 0.508)
			(layers "B.Cu" "B.Mask" "B.Paste")
			(net "GND")
		)
		(pad "280" smd rect
			(at -4.59994 119.8499 270)
			(size 1.8034 0.508)
			(layers "B.Cu" "B.Mask" "B.Paste")
			(net "M_J_DQ<63>")
		)
		(pad "281" smd rect
			(at -4.59994 120.700038 270)
			(size 1.8034 0.508)
			(layers "B.Cu" "B.Mask" "B.Paste")
			(net "GND")
		)
		(pad "282" smd rect
			(at -4.59994 121.549922 270)
			(size 1.8034 0.508)
			(layers "B.Cu" "B.Mask" "B.Paste")
			(net "M_J_DQ<59>")
		)
		(pad "283" smd rect
			(at -4.59994 122.40006 270)
			(size 1.8034 0.508)
			(layers "B.Cu" "B.Mask" "B.Paste")
			(net "GND")
		)
		(pad "284" smd rect
			(at -4.59994 123.249944 270)
			(size 1.8034 0.508)
			(layers "B.Cu" "B.Mask" "B.Paste")
			(net "PVPP_GHJ")
		)
		(pad "285" smd rect
			(at -4.59994 124.100082 270)
			(size 1.8034 0.508)
			(layers "B.Cu" "B.Mask" "B.Paste")
			(net "SMB_DDR_GHJ_VPP_SDA")
		)
		(pad "286" smd rect
			(at -4.59994 124.949966 270)
			(size 1.8034 0.508)
			(layers "B.Cu" "B.Mask" "B.Paste")
			(net "PVPP_GHJ")
		)
		(pad "287" smd rect
			(at -4.59994 125.800104 270)
			(size 1.8034 0.508)
			(layers "B.Cu" "B.Mask" "B.Paste")
			(net "PVPP_GHJ")
		)
		(pad "288" smd rect
			(at -4.59994 126.649988 270)
			(size 1.8034 0.508)
			(layers "B.Cu" "B.Mask" "B.Paste")
			(net "PVPP_GHJ")
		)
	)
)
